# SCM (Grand Teton) — schematic netlist excerpt (pin names and nets, part order shuffled) for the footprints in the layout excerpt that follows; sources: Cadence DE-HDL packaged netlist, KiCad conversion of 12092022_DA0F0TMDCD0_F0T_Management_Board_D_brd_V3_OCP.brd

C106  Q_CAP  1UF 25V 10% X6S  pkg C0402  page 16 : A = P1V8_AUX ; B = GND
R618  Q_RES  0 5% CHIP  pkg 0402LF  page 31 : A = UART_SYS_DBG_RX ; B = UART_SYS_DBG_RX_R

(kicad_pcb
	(version 20260206)
	(generator "pcbnew")
	(generator_version "10.0")
	(general
		(thickness 1.6)
		(legacy_teardrops no)
	)
	(paper "A4")
	(title_block
		(title "12092022_DA0F0TMDCD0_F0T_Management_Board_D_brd_V3_OCP.brd")
		(comment 1 "Grand Teton / footprints 934-935 of 1440")
	)
	(layers
		(0 "F.Cu" signal "TOP")
		(4 "In1.Cu" signal "GND")
		(6 "In2.Cu" signal "IN1")
		(8 "In3.Cu" signal "GND1")
		(10 "In4.Cu" signal "IN2")
		(12 "In5.Cu" signal "VCC")
		(14 "In6.Cu" signal "VCC1")
		(16 "In7.Cu" signal "IN3")
		(18 "In8.Cu" signal "GND2")
		(20 "In9.Cu" signal "IN4")
		(22 "In10.Cu" signal "GND3")
		(2 "B.Cu" signal "BOTTOM")
		(9 "F.Adhes" user "F.Adhesive")
		(11 "B.Adhes" user "B.Adhesive")
		(13 "F.Paste" user "Package Geometry/Pastemask Top")
		(15 "B.Paste" user "Package Geometry/Pastemask Bottom")
		(5 "F.SilkS" user "Ref Des/Silkscreen Top")
		(7 "B.SilkS" user "Ref Des/Silkscreen Bottom")
		(1 "F.Mask" user "Board Geometry/Soldermask Top")
		(3 "B.Mask" user "Board Geometry/Soldermask Bottom")
		(17 "Dwgs.User" user "User.Drawings")
		(19 "Cmts.User" user "User.Comments")
		(21 "Eco1.User" user "User.Eco1")
		(23 "Eco2.User" user "User.Eco2")
		(25 "Edge.Cuts" user "Board Geometry/Outline")
		(27 "Margin" user)
		(31 "F.CrtYd" user "Package Geometry/Place Bound Top")
		(29 "B.CrtYd" user "Package Geometry/Place Bound Bottom")
		(35 "F.Fab" user "Ref Des/Assembly Top")
		(33 "B.Fab" user "Ref Des/Assembly Bottom")
	)
	(footprint ""
		(layer "B.Cu")
		(at 34.8488 -63.6778)
		(property "Reference" "R618"
			(at 0 0 0)
			(layer "B.SilkS")
			(hide yes)
			(effects
				(font
					(size 1.27 1.27)
				)
				(justify mirror)
			)
		)
		(property "Value" ""
			(at 0 0 0)
			(layer "B.Fab")
			(effects
				(font
					(size 1.27 1.27)
				)
				(justify mirror)
			)
		)
		(duplicate_pad_numbers_are_jumpers no)
		(fp_line
			(start -0.7874 -0.4064)
			(end -0.7874 0.4064)
			(stroke
				(width 0.1524)
				(type default)
			)
			(layer "B.SilkS")
		)
		(fp_line
			(start -0.7874 0.4064)
			(end 0.7874 0.4064)
			(stroke
				(width 0.1524)
				(type default)
			)
			(layer "B.SilkS")
		)
		(fp_line
			(start 0.7874 -0.4064)
			(end -0.7874 -0.4064)
			(stroke
				(width 0.1524)
				(type default)
			)
			(layer "B.SilkS")
		)
		(fp_line
			(start 0.7874 0.4064)
			(end 0.7874 -0.4064)
			(stroke
				(width 0.1524)
				(type default)
			)
			(layer "B.SilkS")
		)
		(fp_line
			(start -0.67945 -0.3048)
			(end -0.67945 0.3048)
			(stroke
				(width 0.1)
				(type default)
			)
			(layer "B.Fab")
		)
		(fp_line
			(start -0.67945 0.3048)
			(end -0.120396 0.3048)
			(stroke
				(width 0.1)
				(type default)
			)
			(layer "B.Fab")
		)
		(fp_line
			(start -0.12065 -0.3048)
			(end -0.67945 -0.3048)
			(stroke
				(width 0.1)
				(type default)
			)
			(layer "B.Fab")
		)
		(fp_line
			(start -0.12065 -0.2794)
			(end -0.12065 -0.3048)
			(stroke
				(width 0.1)
				(type default)
			)
			(layer "B.Fab")
		)
		(fp_line
			(start -0.120396 0.2794)
			(end 0.12065 0.2794)
			(stroke
				(width 0.1)
				(type default)
			)
			(layer "B.Fab")
		)
		(fp_line
			(start -0.120396 0.3048)
			(end -0.120396 0.2794)
			(stroke
				(width 0.1)
				(type default)
			)
			(layer "B.Fab")
		)
		(fp_line
			(start 0.12065 -0.305054)
			(end 0.12065 -0.2794)
			(stroke
				(width 0.1)
				(type default)
			)
			(layer "B.Fab")
		)
		(fp_line
			(start 0.12065 -0.2794)
			(end -0.12065 -0.2794)
			(stroke
				(width 0.1)
				(type default)
			)
			(layer "B.Fab")
		)
		(fp_line
			(start 0.12065 0.2794)
			(end 0.12065 0.3048)
			(stroke
				(width 0.1)
				(type default)
			)
			(layer "B.Fab")
		)
		(fp_line
			(start 0.12065 0.3048)
			(end 0.67945 0.3048)
			(stroke
				(width 0.1)
				(type default)
			)
			(layer "B.Fab")
		)
		(fp_line
			(start 0.67945 -0.305054)
			(end 0.12065 -0.305054)
			(stroke
				(width 0.1)
				(type default)
			)
			(layer "B.Fab")
		)
		(fp_line
			(start 0.67945 0.3048)
			(end 0.67945 -0.305054)
			(stroke
				(width 0.1)
				(type default)
			)
			(layer "B.Fab")
		)
		(pad "1" smd circle
			(at 0.40005 0 180)
			(size 0 0)
			(layers "B.Cu" "B.Mask" "B.Paste")
			(net "UART_SYS_DBG_RX")
		)
		(pad "2" smd circle
			(at -0.40005 0 180)
			(size 0 0)
			(layers "B.Cu" "B.Mask" "B.Paste")
			(net "UART_SYS_DBG_RX_R")
		)
	)
	(footprint ""
		(layer "B.Cu")
		(at 55.123334 -54.87162)
		(property "Reference" "C106"
			(at 0 0 0)
			(layer "B.SilkS")
			(hide yes)
			(effects
				(font
					(size 1.27 1.27)
				)
				(justify mirror)
			)
		)
		(property "Value" ""
			(at 0 0 0)
			(layer "B.Fab")
			(effects
				(font
					(size 1.27 1.27)
				)
				(justify mirror)
			)
		)
		(duplicate_pad_numbers_are_jumpers no)
		(fp_line
			(start -0.7874 -0.4064)
			(end -0.7874 0.4064)
			(stroke
				(width 0.1524)
				(type default)
			)
			(layer "B.SilkS")
		)
		(fp_line
			(start -0.7874 0.4064)
			(end 0.7874 0.4064)
			(stroke
				(width 0.1524)
				(type default)
			)
			(layer "B.SilkS")
		)
		(fp_line
			(start 0.7874 -0.4064)
			(end -0.7874 -0.4064)
			(stroke
				(width 0.1524)
				(type default)
			)
			(layer "B.SilkS")
		)
		(fp_line
			(start 0.7874 0.4064)
			(end 0.7874 -0.4064)
			(stroke
				(width 0.1524)
				(type default)
			)
			(layer "B.SilkS")
		)
		(fp_line
			(start -0.67945 -0.3048)
			(end -0.67945 0.3048)
			(stroke
				(width 0.1)
				(type default)
			)
			(layer "B.Fab")
		)
		(fp_line
			(start -0.67945 0.3048)
			(end -0.120396 0.3048)
			(stroke
				(width 0.1)
				(type default)
			)
			(layer "B.Fab")
		)
		(fp_line
			(start -0.12065 -0.3048)
			(end -0.67945 -0.3048)
			(stroke
				(width 0.1)
				(type default)
			)
			(layer "B.Fab")
		)
		(fp_line
			(start -0.12065 -0.2794)
			(end -0.12065 -0.3048)
			(stroke
				(width 0.1)
				(type default)
			)
			(layer "B.Fab")
		)
		(fp_line
			(start -0.120396 0.2794)
			(end 0.12065 0.2794)
			(stroke
				(width 0.1)
				(type default)
			)
			(layer "B.Fab")
		)
		(fp_line
			(start -0.120396 0.3048)
			(end -0.120396 0.2794)
			(stroke
				(width 0.1)
				(type default)
			)
			(layer "B.Fab")
		)
		(fp_line
			(start 0.12065 -0.305054)
			(end 0.12065 -0.2794)
			(stroke
				(width 0.1)
				(type default)
			)
			(layer "B.Fab")
		)
		(fp_line
			(start 0.12065 -0.2794)
			(end -0.12065 -0.2794)
			(stroke
				(width 0.1)
				(type default)
			)
			(layer "B.Fab")
		)
		(fp_line
			(start 0.12065 0.2794)
			(end 0.12065 0.3048)
			(stroke
				(width 0.1)
				(type default)
			)
			(layer "B.Fab")
		)
		(fp_line
			(start 0.12065 0.3048)
			(end 0.67945 0.3048)
			(stroke
				(width 0.1)
				(type default)
			)
			(layer "B.Fab")
		)
		(fp_line
			(start 0.67945 -0.305054)
			(end 0.12065 -0.305054)
			(stroke
				(width 0.1)
				(type default)
			)
			(layer "B.Fab")
		)
		(fp_line
			(start 0.67945 0.3048)
			(end 0.67945 -0.305054)
			(stroke
				(width 0.1)
				(type default)
			)
			(layer "B.Fab")
		)
		(pad "1" smd circle
			(at 0.40005 0 180)
			(size 0 0)
			(layers "B.Cu" "B.Mask" "B.Paste")
			(net "P1V8_AUX")
		)
		(pad "2" smd circle
			(at -0.40005 0 180)
			(size 0 0)
			(layers "B.Cu" "B.Mask" "B.Paste")
			(net "GND")
		)
	)
)
